# TIMECARD (Time Appliance Project (Time Card)) — schematic netlist excerpt (pin names and nets, part order shuffled) for the footprints in the layout excerpt that follows; sources: Cadence DE-HDL packaged netlist, KiCad conversion of R4006-B0001-02_R01.brd

R189  RESISTOR  3.24KOHM 1%  pkg SMC_0402R_H014  page 30 : \1\ = SG ; \2\ = XP1R2V_FB
SP45  NULL  pkg DUMMY  page 34
R285  RESISTOR  10KOHM 1%  pkg SMC_0402R_H016  page 25 : \1\ = XP3R3V_FPGA ; \2\ = FPGA_IO_3

(kicad_pcb
	(version 20260206)
	(generator "pcbnew")
	(generator_version "10.0")
	(general
		(thickness 1.6)
		(legacy_teardrops no)
	)
	(paper "A4")
	(title_block
		(title "timecard-production-celestica-r4006 — R4006-B0001-02_R01.brd")
		(comment 1 "Time Appliance Project (Time Card) / footprints 336-338 of 1113")
	)
	(layers
		(0 "F.Cu" signal "TOP")
		(4 "In1.Cu" signal "L02_GND1")
		(6 "In2.Cu" signal "L03_SIG1")
		(8 "In3.Cu" signal "L04_GND2")
		(10 "In4.Cu" signal "L05_VCC1")
		(12 "In5.Cu" signal "L06_VCC2")
		(14 "In6.Cu" signal "L07_GND3")
		(16 "In7.Cu" signal "L08_SIG2")
		(18 "In8.Cu" signal "L09_GND4")
		(2 "B.Cu" signal "BOTTOM")
		(9 "F.Adhes" user "F.Adhesive")
		(11 "B.Adhes" user "B.Adhesive")
		(13 "F.Paste" user "Package Geometry/Pastemask Top")
		(15 "B.Paste" user "Package Geometry/Pastemask Bottom")
		(5 "F.SilkS" user "Ref Des/Silkscreen Top")
		(7 "B.SilkS" user "Ref Des/Silkscreen Bottom")
		(1 "F.Mask" user "Board Geometry/Soldermask Top")
		(3 "B.Mask" user "Board Geometry/Soldermask Bottom")
		(17 "Dwgs.User" user "User.Drawings")
		(19 "Cmts.User" user "User.Comments")
		(21 "Eco1.User" user "User.Eco1")
		(23 "Eco2.User" user "User.Eco2")
		(25 "Edge.Cuts" user "Board Geometry/Outline")
		(27 "Margin" user)
		(31 "F.CrtYd" user "Package Geometry/Place Bound Top")
		(29 "B.CrtYd" user "Package Geometry/Place Bound Bottom")
		(35 "F.Fab" user "Ref Des/Assembly Top")
		(33 "B.Fab" user "Ref Des/Assembly Bottom")
	)
	(footprint ""
		(layer "F.Cu")
		(at 96.5454 -64.2874 -90)
		(property "Reference" "R285"
			(at 2.6924 -0.77597 90)
			(unlocked yes)
			(layer "F.SilkS")
			(effects
				(font
					(size 0.7874 0.5842)
					(thickness 0.1524)
				)
			)
		)
		(property "Value" "VAL*"
			(at 0.02032 2.13233 270)
			(unlocked yes)
			(layer "F.Fab")
			(hide yes)
			(effects
				(font
					(size 0.7874 0.5842)
					(thickness 0.1524)
				)
			)
		)
		(property "Tolerance" "TOL*"
			(at 0.044704 3.05435 270)
			(unlocked yes)
			(layer "Cmts.User")
			(hide yes)
			(effects
				(font
					(size 0.7874 0.5842)
					(thickness 0.1524)
				)
			)
		)
		(property "User Part Number" "PARTNUM*"
			(at 0.02032 4.024884 270)
			(unlocked yes)
			(layer "Cmts.User")
			(hide yes)
			(effects
				(font
					(size 0.7874 0.5842)
					(thickness 0.1524)
				)
			)
		)
		(property "Device Type" "RESISTOR-G155-11002-01,10KOHM,A"
			(at 0.008382 1.210564 270)
			(unlocked yes)
			(layer "F.Fab")
			(hide yes)
			(effects
				(font
					(size 0.7874 0.5842)
					(thickness 0.1524)
				)
			)
		)
		(duplicate_pad_numbers_are_jumpers no)
		(fp_line
			(start -1.143 0.5588)
			(end 1.143 0.5588)
			(stroke
				(width 0.1)
				(type default)
			)
			(layer "F.SilkS")
		)
		(fp_line
			(start 1.143 0.5588)
			(end 1.143 -0.5588)
			(stroke
				(width 0.1)
				(type default)
			)
			(layer "F.SilkS")
		)
		(fp_line
			(start -1.143 -0.5588)
			(end -1.143 0.5588)
			(stroke
				(width 0.1)
				(type default)
			)
			(layer "F.SilkS")
		)
		(fp_line
			(start 1.143 -0.5588)
			(end -1.143 -0.5588)
			(stroke
				(width 0.1)
				(type default)
			)
			(layer "F.SilkS")
		)
		(fp_poly
			(pts
				(xy -1.143 0.5588) (xy 1.143 0.5588) (xy 1.143 -0.5588) (xy -1.143 -0.5588)
			)
			(stroke
				(width 0)
				(type default)
			)
			(fill no)
			(layer "F.CrtYd")
		)
		(fp_line
			(start -0.508 0.3048)
			(end 0.508 0.3048)
			(stroke
				(width 0.1)
				(type default)
			)
			(layer "F.Fab")
		)
		(fp_line
			(start 0.508 0.3048)
			(end 0.508 -0.3048)
			(stroke
				(width 0.1)
				(type default)
			)
			(layer "F.Fab")
		)
		(fp_line
			(start -0.508 -0.3048)
			(end -0.508 0.3048)
			(stroke
				(width 0.1)
				(type default)
			)
			(layer "F.Fab")
		)
		(fp_line
			(start 0.508 -0.3048)
			(end -0.508 -0.3048)
			(stroke
				(width 0.1)
				(type default)
			)
			(layer "F.Fab")
		)
		(pad "1" smd rect
			(at -0.5334 0 270)
			(size 0.7112 0.6096)
			(layers "F.Cu" "F.Mask" "F.Paste")
			(net "XP3R3V_FPGA")
		)
		(pad "2" smd rect
			(at 0.5334 0 270)
			(size 0.7112 0.6096)
			(layers "F.Cu" "F.Mask" "F.Paste")
			(net "FPGA_IO_3")
		)
		(zone
			(layer "F.Cu")
			(hatch none 0.5)
			(connect_pads
				(clearance 0)
			)
			(min_thickness 0.25)
			(keepout
				(tracks not_allowed)
				(vias allowed)
				(pads allowed)
				(copperpour not_allowed)
				(footprints allowed)
			)
			(placement
				(enabled no)
				(sheetname "")
			)
			(fill
				(thermal_gap 0.5)
				(thermal_bridge_width 0.5)
				(island_removal_mode 0)
			)
			(polygon
				(pts
					(xy 96.2406 -64.3636) (xy 96.2406 -64.2112) (xy 96.8502 -64.2112) (xy 96.8502 -64.3636)
				)
			)
		)
		(zone
			(layer "F.Cu")
			(hatch none 0.5)
			(connect_pads
				(clearance 0)
			)
			(min_thickness 0.25)
			(keepout
				(tracks allowed)
				(vias not_allowed)
				(pads allowed)
				(copperpour not_allowed)
				(footprints allowed)
			)
			(placement
				(enabled no)
				(sheetname "")
			)
			(fill
				(thermal_gap 0.5)
				(thermal_bridge_width 0.5)
				(island_removal_mode 0)
			)
			(polygon
				(pts
					(xy 96.2406 -64.3636) (xy 96.2406 -64.2112) (xy 96.8502 -64.2112) (xy 96.8502 -64.3636)
				)
			)
		)
	)
	(footprint ""
		(layer "F.Cu")
		(at 97.4598 -69.215)
		(property "Reference" "R189"
			(at -28.1178 -18.88363 0)
			(unlocked yes)
			(layer "F.SilkS")
			(effects
				(font
					(size 0.7874 0.5842)
					(thickness 0.1524)
				)
			)
		)
		(property "Value" "VAL*"
			(at 0.02032 2.13233 0)
			(unlocked yes)
			(layer "F.Fab")
			(hide yes)
			(effects
				(font
					(size 0.7874 0.5842)
					(thickness 0.1524)
				)
			)
		)
		(property "Tolerance" "TOL*"
			(at 0.044704 3.05435 0)
			(unlocked yes)
			(layer "Cmts.User")
			(hide yes)
			(effects
				(font
					(size 0.7874 0.5842)
					(thickness 0.1524)
				)
			)
		)
		(property "User Part Number" "PARTNUM*"
			(at 0.02032 4.024884 0)
			(unlocked yes)
			(layer "Cmts.User")
			(hide yes)
			(effects
				(font
					(size 0.7874 0.5842)
					(thickness 0.1524)
				)
			)
		)
		(property "Device Type" "RESISTOR-G155-03241-01,3.24KOHA"
			(at 0.008382 1.210564 0)
			(unlocked yes)
			(layer "F.Fab")
			(hide yes)
			(effects
				(font
					(size 0.7874 0.5842)
					(thickness 0.1524)
				)
			)
		)
		(duplicate_pad_numbers_are_jumpers no)
		(fp_line
			(start -1.143 -0.5588)
			(end -1.143 0.5588)
			(stroke
				(width 0.1)
				(type default)
			)
			(layer "F.SilkS")
		)
		(fp_line
			(start -1.143 0.5588)
			(end 1.143 0.5588)
			(stroke
				(width 0.1)
				(type default)
			)
			(layer "F.SilkS")
		)
		(fp_line
			(start 1.143 -0.5588)
			(end -1.143 -0.5588)
			(stroke
				(width 0.1)
				(type default)
			)
			(layer "F.SilkS")
		)
		(fp_line
			(start 1.143 0.5588)
			(end 1.143 -0.5588)
			(stroke
				(width 0.1)
				(type default)
			)
			(layer "F.SilkS")
		)
		(fp_rect
			(start -1.143 -0.5588)
			(end 1.143 0.5588)
			(stroke
				(width 0)
				(type default)
			)
			(fill no)
			(layer "F.CrtYd")
		)
		(fp_line
			(start -0.508 -0.3048)
			(end -0.508 0.3048)
			(stroke
				(width 0.1)
				(type default)
			)
			(layer "F.Fab")
		)
		(fp_line
			(start -0.508 0.3048)
			(end 0.508 0.3048)
			(stroke
				(width 0.1)
				(type default)
			)
			(layer "F.Fab")
		)
		(fp_line
			(start 0.508 -0.3048)
			(end -0.508 -0.3048)
			(stroke
				(width 0.1)
				(type default)
			)
			(layer "F.Fab")
		)
		(fp_line
			(start 0.508 0.3048)
			(end 0.508 -0.3048)
			(stroke
				(width 0.1)
				(type default)
			)
			(layer "F.Fab")
		)
		(pad "1" smd rect
			(at -0.5334 0)
			(size 0.7112 0.6096)
			(layers "F.Cu" "F.Mask" "F.Paste")
			(net "SG")
		)
		(pad "2" smd rect
			(at 0.5334 0)
			(size 0.7112 0.6096)
			(layers "F.Cu" "F.Mask" "F.Paste")
			(net "XP1R2V_FB")
		)
		(zone
			(layer "F.Cu")
			(hatch none 0.5)
			(connect_pads
				(clearance 0)
			)
			(min_thickness 0.25)
			(keepout
				(tracks allowed)
				(vias not_allowed)
				(pads allowed)
				(copperpour not_allowed)
				(footprints allowed)
			)
			(placement
				(enabled no)
				(sheetname "")
			)
			(fill
				(thermal_gap 0.5)
				(thermal_bridge_width 0.5)
				(island_removal_mode 0)
			)
			(polygon
				(pts
					(xy 97.3836 -69.5198) (xy 97.3836 -68.9102) (xy 97.536 -68.9102) (xy 97.536 -69.5198)
				)
			)
		)
	)
	(footprint ""
		(layer "F.Cu")
		(at 59.69 -127.127)
		(property "Reference" "SP45"
			(at 0 0 0)
			(layer "F.SilkS")
			(hide yes)
			(effects
				(font
					(size 1.27 1.27)
				)
			)
		)
		(property "Value" ""
			(at 0 0 0)
			(layer "F.Fab")
			(effects
				(font
					(size 1.27 1.27)
				)
			)
		)
		(duplicate_pad_numbers_are_jumpers no)
	)
)
